# S9S_MB_2U (Grand Teton) — schematic netlist excerpt (pin names and nets, part order shuffled) for the footprints in the layout excerpt that follows; sources: Cadence DE-HDL packaged netlist, KiCad conversion of 03242023_DA0F0TMBIJ0_F0T_Motherboard_J_brd_V01_OCP.brd

C623  Q_CAP  1UF 25V 10% EMPTY  pkg C0402  page 129 : A = RST_PLD_CPU0_DRAM_CD_N ; B = GND
R291  Q_RES  240 1% EMPTY  pkg 0402LF  page 119 : A = GND ; B = PD_CPU1_ENH_MCECC_DIS

(kicad_pcb
	(version 20260206)
	(generator "pcbnew")
	(generator_version "10.0")
	(general
		(thickness 1.6)
		(legacy_teardrops no)
	)
	(paper "A4")
	(title_block
		(title "03242023_DA0F0TMBIJ0_F0T_Motherboard_J_brd_V01_OCP.brd")
		(comment 1 "Grand Teton / footprints 5511-5512 of 6105")
	)
	(layers
		(0 "F.Cu" signal "TOP")
		(4 "In1.Cu" signal "GND")
		(6 "In2.Cu" signal "IN1")
		(8 "In3.Cu" signal "GND1")
		(10 "In4.Cu" signal "IN2")
		(12 "In5.Cu" signal "GND2")
		(14 "In6.Cu" signal "IN3")
		(16 "In7.Cu" signal "GND3")
		(18 "In8.Cu" signal "VCC")
		(20 "In9.Cu" signal "VCC1")
		(22 "In10.Cu" signal "GND4")
		(24 "In11.Cu" signal "IN4")
		(26 "In12.Cu" signal "GND5")
		(28 "In13.Cu" signal "IN5")
		(30 "In14.Cu" signal "GND6")
		(32 "In15.Cu" signal "IN6")
		(34 "In16.Cu" signal "GND7")
		(2 "B.Cu" signal "BOTTOM")
		(9 "F.Adhes" user "F.Adhesive")
		(11 "B.Adhes" user "B.Adhesive")
		(13 "F.Paste" user "Package Geometry/Pastemask Top")
		(15 "B.Paste" user "Package Geometry/Pastemask Bottom")
		(5 "F.SilkS" user "Ref Des/Silkscreen Top")
		(7 "B.SilkS" user "Ref Des/Silkscreen Bottom")
		(1 "F.Mask" user "Board Geometry/Soldermask Top")
		(3 "B.Mask" user "Board Geometry/Soldermask Bottom")
		(17 "Dwgs.User" user "User.Drawings")
		(19 "Cmts.User" user "User.Comments")
		(21 "Eco1.User" user "User.Eco1")
		(23 "Eco2.User" user "User.Eco2")
		(25 "Edge.Cuts" user "Board Geometry/Outline")
		(27 "Margin" user)
		(31 "F.CrtYd" user "Package Geometry/Place Bound Top")
		(29 "B.CrtYd" user "Package Geometry/Place Bound Bottom")
		(35 "F.Fab" user "Ref Des/Assembly Top")
		(33 "B.Fab" user "Ref Des/Assembly Bottom")
	)
	(footprint ""
		(layer "B.Cu")
		(at 268.668246 -193.503296 -90)
		(property "Reference" "C623"
			(at 0 0 90)
			(layer "B.SilkS")
			(hide yes)
			(effects
				(font
					(size 1.27 1.27)
				)
				(justify mirror)
			)
		)
		(property "Value" ""
			(at 0 0 90)
			(layer "B.Fab")
			(effects
				(font
					(size 1.27 1.27)
				)
				(justify mirror)
			)
		)
		(duplicate_pad_numbers_are_jumpers no)
		(fp_line
			(start -0.7874 0.4064)
			(end 0.7874 0.4064)
			(stroke
				(width 0.1524)
				(type default)
			)
			(layer "B.SilkS")
		)
		(fp_line
			(start 0.7874 0.4064)
			(end 0.7874 -0.4064)
			(stroke
				(width 0.1524)
				(type default)
			)
			(layer "B.SilkS")
		)
		(fp_line
			(start -0.7874 -0.4064)
			(end -0.7874 0.4064)
			(stroke
				(width 0.1524)
				(type default)
			)
			(layer "B.SilkS")
		)
		(fp_line
			(start 0.7874 -0.4064)
			(end -0.7874 -0.4064)
			(stroke
				(width 0.1524)
				(type default)
			)
			(layer "B.SilkS")
		)
		(fp_line
			(start -0.67945 0.3048)
			(end -0.120396 0.3048)
			(stroke
				(width 0.1)
				(type default)
			)
			(layer "B.Fab")
		)
		(fp_line
			(start -0.120396 0.3048)
			(end -0.120396 0.2794)
			(stroke
				(width 0.1)
				(type default)
			)
			(layer "B.Fab")
		)
		(fp_line
			(start 0.12065 0.3048)
			(end 0.67945 0.3048)
			(stroke
				(width 0.1)
				(type default)
			)
			(layer "B.Fab")
		)
		(fp_line
			(start 0.67945 0.3048)
			(end 0.67945 -0.305054)
			(stroke
				(width 0.1)
				(type default)
			)
			(layer "B.Fab")
		)
		(fp_line
			(start -0.120396 0.2794)
			(end 0.12065 0.2794)
			(stroke
				(width 0.1)
				(type default)
			)
			(layer "B.Fab")
		)
		(fp_line
			(start 0.12065 0.2794)
			(end 0.12065 0.3048)
			(stroke
				(width 0.1)
				(type default)
			)
			(layer "B.Fab")
		)
		(fp_line
			(start -0.12065 -0.2794)
			(end -0.12065 -0.3048)
			(stroke
				(width 0.1)
				(type default)
			)
			(layer "B.Fab")
		)
		(fp_line
			(start 0.12065 -0.2794)
			(end -0.12065 -0.2794)
			(stroke
				(width 0.1)
				(type default)
			)
			(layer "B.Fab")
		)
		(fp_line
			(start -0.67945 -0.3048)
			(end -0.67945 0.3048)
			(stroke
				(width 0.1)
				(type default)
			)
			(layer "B.Fab")
		)
		(fp_line
			(start -0.12065 -0.3048)
			(end -0.67945 -0.3048)
			(stroke
				(width 0.1)
				(type default)
			)
			(layer "B.Fab")
		)
		(fp_line
			(start 0.12065 -0.305054)
			(end 0.12065 -0.2794)
			(stroke
				(width 0.1)
				(type default)
			)
			(layer "B.Fab")
		)
		(fp_line
			(start 0.67945 -0.305054)
			(end 0.12065 -0.305054)
			(stroke
				(width 0.1)
				(type default)
			)
			(layer "B.Fab")
		)
		(pad "1" smd circle
			(at 0.40005 0 90)
			(size 0 0)
			(layers "B.Cu" "B.Mask" "B.Paste")
			(net "RST_PLD_CPU0_DRAM_CD_N")
		)
		(pad "2" smd circle
			(at -0.40005 0 90)
			(size 0 0)
			(layers "B.Cu" "B.Mask" "B.Paste")
			(net "GND")
		)
	)
	(footprint ""
		(layer "B.Cu")
		(at 149.099524 -189.963298 180)
		(property "Reference" "R291"
			(at 0 0 0)
			(layer "B.SilkS")
			(hide yes)
			(effects
				(font
					(size 1.27 1.27)
				)
				(justify mirror)
			)
		)
		(property "Value" ""
			(at 0 0 0)
			(layer "B.Fab")
			(effects
				(font
					(size 1.27 1.27)
				)
				(justify mirror)
			)
		)
		(duplicate_pad_numbers_are_jumpers no)
		(fp_line
			(start 0.7874 0.4064)
			(end 0.7874 -0.4064)
			(stroke
				(width 0.1524)
				(type default)
			)
			(layer "B.SilkS")
		)
		(fp_line
			(start 0.7874 -0.4064)
			(end -0.7874 -0.4064)
			(stroke
				(width 0.1524)
				(type default)
			)
			(layer "B.SilkS")
		)
		(fp_line
			(start -0.7874 0.4064)
			(end 0.7874 0.4064)
			(stroke
				(width 0.1524)
				(type default)
			)
			(layer "B.SilkS")
		)
		(fp_line
			(start -0.7874 -0.4064)
			(end -0.7874 0.4064)
			(stroke
				(width 0.1524)
				(type default)
			)
			(layer "B.SilkS")
		)
		(fp_line
			(start 0.67945 0.3048)
			(end 0.67945 -0.305054)
			(stroke
				(width 0.1)
				(type default)
			)
			(layer "B.Fab")
		)
		(fp_line
			(start 0.67945 -0.305054)
			(end 0.12065 -0.305054)
			(stroke
				(width 0.1)
				(type default)
			)
			(layer "B.Fab")
		)
		(fp_line
			(start 0.12065 0.3048)
			(end 0.67945 0.3048)
			(stroke
				(width 0.1)
				(type default)
			)
			(layer "B.Fab")
		)
		(fp_line
			(start 0.12065 0.2794)
			(end 0.12065 0.3048)
			(stroke
				(width 0.1)
				(type default)
			)
			(layer "B.Fab")
		)
		(fp_line
			(start 0.12065 -0.2794)
			(end -0.12065 -0.2794)
			(stroke
				(width 0.1)
				(type default)
			)
			(layer "B.Fab")
		)
		(fp_line
			(start 0.12065 -0.305054)
			(end 0.12065 -0.2794)
			(stroke
				(width 0.1)
				(type default)
			)
			(layer "B.Fab")
		)
		(fp_line
			(start -0.120396 0.3048)
			(end -0.120396 0.2794)
			(stroke
				(width 0.1)
				(type default)
			)
			(layer "B.Fab")
		)
		(fp_line
			(start -0.120396 0.2794)
			(end 0.12065 0.2794)
			(stroke
				(width 0.1)
				(type default)
			)
			(layer "B.Fab")
		)
		(fp_line
			(start -0.12065 -0.2794)
			(end -0.12065 -0.3048)
			(stroke
				(width 0.1)
				(type default)
			)
			(layer "B.Fab")
		)
		(fp_line
			(start -0.12065 -0.3048)
			(end -0.67945 -0.3048)
			(stroke
				(width 0.1)
				(type default)
			)
			(layer "B.Fab")
		)
		(fp_line
			(start -0.67945 0.3048)
			(end -0.120396 0.3048)
			(stroke
				(width 0.1)
				(type default)
			)
			(layer "B.Fab")
		)
		(fp_line
			(start -0.67945 -0.3048)
			(end -0.67945 0.3048)
			(stroke
				(width 0.1)
				(type default)
			)
			(layer "B.Fab")
		)
		(pad "1" smd circle
			(at 0.40005 0)
			(size 0 0)
			(layers "B.Cu" "B.Mask" "B.Paste")
			(net "GND")
		)
		(pad "2" smd circle
			(at -0.40005 0)
			(size 0 0)
			(layers "B.Cu" "B.Mask" "B.Paste")
			(net "PD_CPU1_ENH_MCECC_DIS")
		)
	)
)
